(kicad_pcb
	(version 20260206)
	(generator "pcbnew")
	(generator_version "10.0")
	(general
		(thickness 1.6)
		(legacy_teardrops no)
	)
	(paper "A4")
	(title_block
		(title "04192023_DAF0TMB3IC0_F0TG_MB_C_brd_V02_OCP.brd")
		(comment 1 "Grand Teton / footprints 1644-1649 of 8354")
	)
	(layers
		(0 "F.Cu" signal "TOP")
		(4 "In1.Cu" signal "GND")
		(6 "In2.Cu" signal "IN1")
		(8 "In3.Cu" signal "GND1")
		(10 "In4.Cu" signal "IN2")
		(12 "In5.Cu" signal "GND2")
		(14 "In6.Cu" signal "IN3")
		(16 "In7.Cu" signal "GND3")
		(18 "In8.Cu" signal "VCC")
		(20 "In9.Cu" signal "VCC1")
		(22 "In10.Cu" signal "GND4")
		(24 "In11.Cu" signal "IN4")
		(26 "In12.Cu" signal "GND5")
		(28 "In13.Cu" signal "IN5")
		(30 "In14.Cu" signal "GND6")
		(32 "In15.Cu" signal "IN6")
		(34 "In16.Cu" signal "GND7")
		(2 "B.Cu" signal "BOTTOM")
		(9 "F.Adhes" user "F.Adhesive")
		(11 "B.Adhes" user "B.Adhesive")
		(13 "F.Paste" user "Package Geometry/Pastemask Top")
		(15 "B.Paste" user "Package Geometry/Pastemask Bottom")
		(5 "F.SilkS" user "Ref Des/Silkscreen Top")
		(7 "B.SilkS" user "Ref Des/Silkscreen Bottom")
		(1 "F.Mask" user "Board Geometry/Soldermask Top")
		(3 "B.Mask" user "Board Geometry/Soldermask Bottom")
		(17 "Dwgs.User" user "User.Drawings")
		(19 "Cmts.User" user "User.Comments")
		(21 "Eco1.User" user "User.Eco1")
		(23 "Eco2.User" user "User.Eco2")
		(25 "Edge.Cuts" user "Board Geometry/Outline")
		(27 "Margin" user)
		(31 "F.CrtYd" user "Package Geometry/Place Bound Top")
		(29 "B.CrtYd" user "Package Geometry/Place Bound Bottom")
		(35 "F.Fab" user "Ref Des/Assembly Top")
		(33 "B.Fab" user "Ref Des/Assembly Bottom")
	)
	(footprint ""
		(layer "F.Cu")
		(at 323.637148 -45.86351 180)
		(property "Reference" "R3865"
			(at 0 0 180)
			(layer "F.SilkS")
			(hide yes)
			(effects
				(font
					(size 1.27 1.27)
				)
			)
		)
		(property "Value" ""
			(at 0 0 180)
			(layer "F.Fab")
			(effects
				(font
					(size 1.27 1.27)
				)
			)
		)
		(duplicate_pad_numbers_are_jumpers no)
		(fp_line
			(start 0.7874 0.4064)
			(end -0.7874 0.4064)
			(stroke
				(width 0.1524)
				(type default)
			)
			(layer "F.SilkS")
		)
		(fp_line
			(start 0.7874 -0.4064)
			(end 0.7874 0.4064)
			(stroke
				(width 0.1524)
				(type default)
			)
			(layer "F.SilkS")
		)
		(fp_line
			(start -0.7874 0.4064)
			(end -0.7874 -0.4064)
			(stroke
				(width 0.1524)
				(type default)
			)
			(layer "F.SilkS")
		)
		(fp_line
			(start -0.7874 -0.4064)
			(end 0.7874 -0.4064)
			(stroke
				(width 0.1524)
				(type default)
			)
			(layer "F.SilkS")
		)
		(fp_line
			(start 0.67945 0.3048)
			(end 0.120396 0.3048)
			(stroke
				(width 0.1)
				(type default)
			)
			(layer "F.Fab")
		)
		(fp_line
			(start 0.67945 -0.3048)
			(end 0.67945 0.3048)
			(stroke
				(width 0.1)
				(type default)
			)
			(layer "F.Fab")
		)
		(fp_line
			(start 0.12065 -0.2794)
			(end 0.12065 -0.3048)
			(stroke
				(width 0.1)
				(type default)
			)
			(layer "F.Fab")
		)
		(fp_line
			(start 0.12065 -0.3048)
			(end 0.67945 -0.3048)
			(stroke
				(width 0.1)
				(type default)
			)
			(layer "F.Fab")
		)
		(fp_line
			(start 0.120396 0.3048)
			(end 0.120396 0.2794)
			(stroke
				(width 0.1)
				(type default)
			)
			(layer "F.Fab")
		)
		(fp_line
			(start 0.120396 0.2794)
			(end -0.12065 0.2794)
			(stroke
				(width 0.1)
				(type default)
			)
			(layer "F.Fab")
		)
		(fp_line
			(start -0.12065 0.3048)
			(end -0.67945 0.3048)
			(stroke
				(width 0.1)
				(type default)
			)
			(layer "F.Fab")
		)
		(fp_line
			(start -0.12065 0.2794)
			(end -0.12065 0.3048)
			(stroke
				(width 0.1)
				(type default)
			)
			(layer "F.Fab")
		)
		(fp_line
			(start -0.12065 -0.2794)
			(end 0.12065 -0.2794)
			(stroke
				(width 0.1)
				(type default)
			)
			(layer "F.Fab")
		)
		(fp_line
			(start -0.12065 -0.305054)
			(end -0.12065 -0.2794)
			(stroke
				(width 0.1)
				(type default)
			)
			(layer "F.Fab")
		)
		(fp_line
			(start -0.67945 0.3048)
			(end -0.67945 -0.305054)
			(stroke
				(width 0.1)
				(type default)
			)
			(layer "F.Fab")
		)
		(fp_line
			(start -0.67945 -0.305054)
			(end -0.12065 -0.305054)
			(stroke
				(width 0.1)
				(type default)
			)
			(layer "F.Fab")
		)
		(pad "1" smd rect
			(at -0.40005 0)
			(size 0.4572 0.508)
			(layers "F.Cu" "F.Mask" "F.Paste")
			(net "P12V_OCP_SFF_ISENSE_MAM_TIC")
		)
		(pad "2" smd rect
			(at 0.40005 0)
			(size 0.4572 0.508)
			(layers "F.Cu" "F.Mask" "F.Paste")
			(net "P12V_OCP_SFF_ISENSE_TIC")
		)
	)
	(footprint ""
		(layer "F.Cu")
		(at 387.623304 -178.0921 90)
		(property "Reference" "PC561"
			(at 0 0 90)
			(layer "F.SilkS")
			(hide yes)
			(effects
				(font
					(size 1.27 1.27)
				)
			)
		)
		(property "Value" ""
			(at 0 0 90)
			(layer "F.Fab")
			(effects
				(font
					(size 1.27 1.27)
				)
			)
		)
		(duplicate_pad_numbers_are_jumpers no)
		(fp_line
			(start 0.7874 -0.4064)
			(end 0.7874 0.4064)
			(stroke
				(width 0.1524)
				(type default)
			)
			(layer "F.SilkS")
		)
		(fp_line
			(start -0.7874 -0.4064)
			(end 0.7874 -0.4064)
			(stroke
				(width 0.1524)
				(type default)
			)
			(layer "F.SilkS")
		)
		(fp_line
			(start 0.7874 0.4064)
			(end -0.7874 0.4064)
			(stroke
				(width 0.1524)
				(type default)
			)
			(layer "F.SilkS")
		)
		(fp_line
			(start -0.7874 0.4064)
			(end -0.7874 -0.4064)
			(stroke
				(width 0.1524)
				(type default)
			)
			(layer "F.SilkS")
		)
		(fp_line
			(start -0.12065 -0.305054)
			(end -0.12065 -0.2794)
			(stroke
				(width 0.1)
				(type default)
			)
			(layer "F.Fab")
		)
		(fp_line
			(start -0.67945 -0.305054)
			(end -0.12065 -0.305054)
			(stroke
				(width 0.1)
				(type default)
			)
			(layer "F.Fab")
		)
		(fp_line
			(start 0.67945 -0.3048)
			(end 0.67945 0.3048)
			(stroke
				(width 0.1)
				(type default)
			)
			(layer "F.Fab")
		)
		(fp_line
			(start 0.12065 -0.3048)
			(end 0.67945 -0.3048)
			(stroke
				(width 0.1)
				(type default)
			)
			(layer "F.Fab")
		)
		(fp_line
			(start 0.12065 -0.2794)
			(end 0.12065 -0.3048)
			(stroke
				(width 0.1)
				(type default)
			)
			(layer "F.Fab")
		)
		(fp_line
			(start -0.12065 -0.2794)
			(end 0.12065 -0.2794)
			(stroke
				(width 0.1)
				(type default)
			)
			(layer "F.Fab")
		)
		(fp_line
			(start 0.120396 0.2794)
			(end -0.12065 0.2794)
			(stroke
				(width 0.1)
				(type default)
			)
			(layer "F.Fab")
		)
		(fp_line
			(start -0.12065 0.2794)
			(end -0.12065 0.3048)
			(stroke
				(width 0.1)
				(type default)
			)
			(layer "F.Fab")
		)
		(fp_line
			(start 0.67945 0.3048)
			(end 0.120396 0.3048)
			(stroke
				(width 0.1)
				(type default)
			)
			(layer "F.Fab")
		)
		(fp_line
			(start 0.120396 0.3048)
			(end 0.120396 0.2794)
			(stroke
				(width 0.1)
				(type default)
			)
			(layer "F.Fab")
		)
		(fp_line
			(start -0.12065 0.3048)
			(end -0.67945 0.3048)
			(stroke
				(width 0.1)
				(type default)
			)
			(layer "F.Fab")
		)
		(fp_line
			(start -0.67945 0.3048)
			(end -0.67945 -0.305054)
			(stroke
				(width 0.1)
				(type default)
			)
			(layer "F.Fab")
		)
		(pad "1" smd circle
			(at -0.40005 0 90)
			(size 0 0)
			(layers "F.Cu" "F.Mask" "F.Paste")
			(net "SW_PVDDCR_CPU0_P0_BOOT4_RC")
		)
		(pad "2" smd circle
			(at 0.40005 0 90)
			(size 0 0)
			(layers "F.Cu" "F.Mask" "F.Paste")
			(net "SW_PVDDCR_CPU0_P0_PH4")
		)
	)
	(footprint ""
		(layer "F.Cu")
		(at 257.242056 -122.97537)
		(property "Reference" "R3710"
			(at 0 0 0)
			(layer "F.SilkS")
			(hide yes)
			(effects
				(font
					(size 1.27 1.27)
				)
			)
		)
		(property "Value" ""
			(at 0 0 0)
			(layer "F.Fab")
			(effects
				(font
					(size 1.27 1.27)
				)
			)
		)
		(duplicate_pad_numbers_are_jumpers no)
		(fp_line
			(start -0.7874 -0.4064)
			(end 0.7874 -0.4064)
			(stroke
				(width 0.1524)
				(type default)
			)
			(layer "F.SilkS")
		)
		(fp_line
			(start -0.7874 0.4064)
			(end -0.7874 -0.4064)
			(stroke
				(width 0.1524)
				(type default)
			)
			(layer "F.SilkS")
		)
		(fp_line
			(start 0.7874 -0.4064)
			(end 0.7874 0.4064)
			(stroke
				(width 0.1524)
				(type default)
			)
			(layer "F.SilkS")
		)
		(fp_line
			(start 0.7874 0.4064)
			(end -0.7874 0.4064)
			(stroke
				(width 0.1524)
				(type default)
			)
			(layer "F.SilkS")
		)
		(fp_line
			(start -0.67945 -0.305054)
			(end -0.12065 -0.305054)
			(stroke
				(width 0.1)
				(type default)
			)
			(layer "F.Fab")
		)
		(fp_line
			(start -0.67945 0.3048)
			(end -0.67945 -0.305054)
			(stroke
				(width 0.1)
				(type default)
			)
			(layer "F.Fab")
		)
		(fp_line
			(start -0.12065 -0.305054)
			(end -0.12065 -0.2794)
			(stroke
				(width 0.1)
				(type default)
			)
			(layer "F.Fab")
		)
		(fp_line
			(start -0.12065 -0.2794)
			(end 0.12065 -0.2794)
			(stroke
				(width 0.1)
				(type default)
			)
			(layer "F.Fab")
		)
		(fp_line
			(start -0.12065 0.2794)
			(end -0.12065 0.3048)
			(stroke
				(width 0.1)
				(type default)
			)
			(layer "F.Fab")
		)
		(fp_line
			(start -0.12065 0.3048)
			(end -0.67945 0.3048)
			(stroke
				(width 0.1)
				(type default)
			)
			(layer "F.Fab")
		)
		(fp_line
			(start 0.120396 0.2794)
			(end -0.12065 0.2794)
			(stroke
				(width 0.1)
				(type default)
			)
			(layer "F.Fab")
		)
		(fp_line
			(start 0.120396 0.3048)
			(end 0.120396 0.2794)
			(stroke
				(width 0.1)
				(type default)
			)
			(layer "F.Fab")
		)
		(fp_line
			(start 0.12065 -0.3048)
			(end 0.67945 -0.3048)
			(stroke
				(width 0.1)
				(type default)
			)
			(layer "F.Fab")
		)
		(fp_line
			(start 0.12065 -0.2794)
			(end 0.12065 -0.3048)
			(stroke
				(width 0.1)
				(type default)
			)
			(layer "F.Fab")
		)
		(fp_line
			(start 0.67945 -0.3048)
			(end 0.67945 0.3048)
			(stroke
				(width 0.1)
				(type default)
			)
			(layer "F.Fab")
		)
		(fp_line
			(start 0.67945 0.3048)
			(end 0.120396 0.3048)
			(stroke
				(width 0.1)
				(type default)
			)
			(layer "F.Fab")
		)
		(pad "1" smd circle
			(at -0.40005 0)
			(size 0 0)
			(layers "F.Cu" "F.Mask" "F.Paste")
			(net "RST_SMB_SWITCH_N")
		)
		(pad "2" smd circle
			(at 0.40005 0)
			(size 0 0)
			(layers "F.Cu" "F.Mask" "F.Paste")
			(net "PU_RST_SMB_PCIE2_N")
		)
	)
	(footprint ""
		(layer "F.Cu")
		(at 68.212462 -37.389562 180)
		(property "Reference" "R3559"
			(at 0 0 180)
			(layer "F.SilkS")
			(hide yes)
			(effects
				(font
					(size 1.27 1.27)
				)
			)
		)
		(property "Value" ""
			(at 0 0 180)
			(layer "F.Fab")
			(effects
				(font
					(size 1.27 1.27)
				)
			)
		)
		(duplicate_pad_numbers_are_jumpers no)
		(fp_line
			(start 0.7874 0.4064)
			(end -0.7874 0.4064)
			(stroke
				(width 0.1524)
				(type default)
			)
			(layer "F.SilkS")
		)
		(fp_line
			(start 0.7874 -0.4064)
			(end 0.7874 0.4064)
			(stroke
				(width 0.1524)
				(type default)
			)
			(layer "F.SilkS")
		)
		(fp_line
			(start -0.7874 0.4064)
			(end -0.7874 -0.4064)
			(stroke
				(width 0.1524)
				(type default)
			)
			(layer "F.SilkS")
		)
		(fp_line
			(start -0.7874 -0.4064)
			(end 0.7874 -0.4064)
			(stroke
				(width 0.1524)
				(type default)
			)
			(layer "F.SilkS")
		)
		(fp_line
			(start 0.67945 0.3048)
			(end 0.120396 0.3048)
			(stroke
				(width 0.1)
				(type default)
			)
			(layer "F.Fab")
		)
		(fp_line
			(start 0.67945 -0.3048)
			(end 0.67945 0.3048)
			(stroke
				(width 0.1)
				(type default)
			)
			(layer "F.Fab")
		)
		(fp_line
			(start 0.12065 -0.2794)
			(end 0.12065 -0.3048)
			(stroke
				(width 0.1)
				(type default)
			)
			(layer "F.Fab")
		)
		(fp_line
			(start 0.12065 -0.3048)
			(end 0.67945 -0.3048)
			(stroke
				(width 0.1)
				(type default)
			)
			(layer "F.Fab")
		)
		(fp_line
			(start 0.120396 0.3048)
			(end 0.120396 0.2794)
			(stroke
				(width 0.1)
				(type default)
			)
			(layer "F.Fab")
		)
		(fp_line
			(start 0.120396 0.2794)
			(end -0.12065 0.2794)
			(stroke
				(width 0.1)
				(type default)
			)
			(layer "F.Fab")
		)
		(fp_line
			(start -0.12065 0.3048)
			(end -0.67945 0.3048)
			(stroke
				(width 0.1)
				(type default)
			)
			(layer "F.Fab")
		)
		(fp_line
			(start -0.12065 0.2794)
			(end -0.12065 0.3048)
			(stroke
				(width 0.1)
				(type default)
			)
			(layer "F.Fab")
		)
		(fp_line
			(start -0.12065 -0.2794)
			(end 0.12065 -0.2794)
			(stroke
				(width 0.1)
				(type default)
			)
			(layer "F.Fab")
		)
		(fp_line
			(start -0.12065 -0.305054)
			(end -0.12065 -0.2794)
			(stroke
				(width 0.1)
				(type default)
			)
			(layer "F.Fab")
		)
		(fp_line
			(start -0.67945 0.3048)
			(end -0.67945 -0.305054)
			(stroke
				(width 0.1)
				(type default)
			)
			(layer "F.Fab")
		)
		(fp_line
			(start -0.67945 -0.305054)
			(end -0.12065 -0.305054)
			(stroke
				(width 0.1)
				(type default)
			)
			(layer "F.Fab")
		)
		(pad "1" smd circle
			(at -0.40005 0 180)
			(size 0 0)
			(layers "F.Cu" "F.Mask" "F.Paste")
			(net "OCP_V3_2_P3V3_ADC_ALERT_R")
		)
		(pad "2" smd circle
			(at 0.40005 0 180)
			(size 0 0)
			(layers "F.Cu" "F.Mask" "F.Paste")
			(net "OCP_V3_2_P3V3_P12V_ADC_R_ALERT")
		)
	)
	(footprint ""
		(layer "F.Cu")
		(at 359.58526 -152.71242 90)
		(property "Reference" "PC492"
			(at 4.049268 -0.80264 0)
			(unlocked yes)
			(layer "F.SilkS")
			(effects
				(font
					(size 0.7874 0.5842)
					(thickness 0.1524)
				)
				(justify left)
			)
		)
		(property "Value" ""
			(at 0 0 90)
			(layer "F.Fab")
			(effects
				(font
					(size 1.27 1.27)
				)
			)
		)
		(duplicate_pad_numbers_are_jumpers no)
		(fp_line
			(start -3.400044 1.249934)
			(end 3.400044 1.249934)
			(stroke
				(width 0.1524)
				(type default)
			)
			(layer "F.SilkS")
		)
		(fp_circle
			(center 0 1.249934)
			(end 0 4.649978)
			(stroke
				(width 0.1524)
				(type default)
			)
			(fill no)
			(layer "F.SilkS")
		)
		(fp_poly
			(pts
				(arc
					(start 3.400044 1.249934)
					(mid 0 4.649978)
					(end -3.400044 1.249934)
				)
			)
			(stroke
				(width 0)
				(type default)
			)
			(fill yes)
			(layer "F.SilkS")
		)
		(fp_circle
			(center 0 1.249934)
			(end 0 4.649978)
			(stroke
				(width 0.1)
				(type default)
			)
			(fill no)
			(layer "F.Fab")
		)
		(pad "1" thru_hole rect
			(at 0 0 90)
			(size 1.524 1.524)
			(drill 1.016)
			(layers "*.Cu" "*.Mask")
			(remove_unused_layers no)
			(net "SW_P12V_AUX_PVDDCR_CPU0_P0_FLT")
			(clearance 0)
			(padstack
				(mode front_inner_back)
				(layer "Inner"
					(shape circle)
					(size 1.524 1.524)
					(clearance 0)
				)
				(layer "B.Cu"
					(shape rect)
					(size 1.524 1.524)
					(clearance 0)
				)
			)
		)
		(pad "2" thru_hole circle
			(at 0 2.500122 90)
			(size 1.524 1.524)
			(drill 1.016)
			(layers "*.Cu" "*.Mask")
			(remove_unused_layers no)
			(net "GND")
			(clearance 0)
		)
	)
	(footprint ""
		(layer "F.Cu")
		(at 230.644192 -294.936926 180)
		(property "Reference" "PC6524"
			(at 0 0 180)
			(layer "F.SilkS")
			(hide yes)
			(effects
				(font
					(size 1.27 1.27)
				)
			)
		)
		(property "Value" ""
			(at 0 0 180)
			(layer "F.Fab")
			(effects
				(font
					(size 1.27 1.27)
				)
			)
		)
		(duplicate_pad_numbers_are_jumpers no)
		(fp_line
			(start 0.7874 0.4064)
			(end -0.7874 0.4064)
			(stroke
				(width 0.1524)
				(type default)
			)
			(layer "F.SilkS")
		)
		(fp_line
			(start 0.7874 -0.4064)
			(end 0.7874 0.4064)
			(stroke
				(width 0.1524)
				(type default)
			)
			(layer "F.SilkS")
		)
		(fp_line
			(start -0.7874 0.4064)
			(end -0.7874 -0.4064)
			(stroke
				(width 0.1524)
				(type default)
			)
			(layer "F.SilkS")
		)
		(fp_line
			(start -0.7874 -0.4064)
			(end 0.7874 -0.4064)
			(stroke
				(width 0.1524)
				(type default)
			)
			(layer "F.SilkS")
		)
		(fp_line
			(start 0.67945 0.3048)
			(end 0.120396 0.3048)
			(stroke
				(width 0.1)
				(type default)
			)
			(layer "F.Fab")
		)
		(fp_line
			(start 0.67945 -0.3048)
			(end 0.67945 0.3048)
			(stroke
				(width 0.1)
				(type default)
			)
			(layer "F.Fab")
		)
		(fp_line
			(start 0.12065 -0.2794)
			(end 0.12065 -0.3048)
			(stroke
				(width 0.1)
				(type default)
			)
			(layer "F.Fab")
		)
		(fp_line
			(start 0.12065 -0.3048)
			(end 0.67945 -0.3048)
			(stroke
				(width 0.1)
				(type default)
			)
			(layer "F.Fab")
		)
		(fp_line
			(start 0.120396 0.3048)
			(end 0.120396 0.2794)
			(stroke
				(width 0.1)
				(type default)
			)
			(layer "F.Fab")
		)
		(fp_line
			(start 0.120396 0.2794)
			(end -0.12065 0.2794)
			(stroke
				(width 0.1)
				(type default)
			)
			(layer "F.Fab")
		)
		(fp_line
			(start -0.12065 0.3048)
			(end -0.67945 0.3048)
			(stroke
				(width 0.1)
				(type default)
			)
			(layer "F.Fab")
		)
		(fp_line
			(start -0.12065 0.2794)
			(end -0.12065 0.3048)
			(stroke
				(width 0.1)
				(type default)
			)
			(layer "F.Fab")
		)
		(fp_line
			(start -0.12065 -0.2794)
			(end 0.12065 -0.2794)
			(stroke
				(width 0.1)
				(type default)
			)
			(layer "F.Fab")
		)
		(fp_line
			(start -0.12065 -0.305054)
			(end -0.12065 -0.2794)
			(stroke
				(width 0.1)
				(type default)
			)
			(layer "F.Fab")
		)
		(fp_line
			(start -0.67945 0.3048)
			(end -0.67945 -0.305054)
			(stroke
				(width 0.1)
				(type default)
			)
			(layer "F.Fab")
		)
		(fp_line
			(start -0.67945 -0.305054)
			(end -0.12065 -0.305054)
			(stroke
				(width 0.1)
				(type default)
			)
			(layer "F.Fab")
		)
		(pad "1" smd circle
			(at -0.40005 0 180)
			(size 0 0)
			(layers "F.Cu" "F.Mask" "F.Paste")
			(net "SW_P12V_AUX_P1V8_RETIMER_CPU1_FLT")
		)
		(pad "2" smd circle
			(at 0.40005 0 180)
			(size 0 0)
			(layers "F.Cu" "F.Mask" "F.Paste")
			(net "GND")
		)
	)
)
